FILE_TYPE = MACRO_DRAWING;
SET COLOR_WIRE YELLOW;
SET COLOR_PROP ORANGE;
SET COLOR_DOT WHITE;
SET COLOR_ARC YELLOW;
SET COLOR_BODY GREEN;
SET COLOR_NOTE PURPLE;
SET PROP_DISPLAY VALUE;
SET PAGE_NUMBER P152;
FORCEADD QUANTA_TITLE_BLOCK_C..1
(0 0);
FORCEPROP 1 LAST CUSTOM_TXT_CDS <NAME_2>
J 0
(-3175 50);
FORCEPROP 1 LAST CUSTOM_TXT_CDS <NAME_1>
J 0
(-3175 175);
FORCEPROP 1 LAST CUSTOM_TXT_CDS <Q_NUMBER>
J 0
(-1403 103);
DISPLAY 1.212766 (-1403 103);
FORCEPROP 1 LAST CUSTOM_TXT_CDS <Q_PROJ>
J 0
(-2382 102);
DISPLAY 1.212766 (-2382 102);
FORCEPROP 1 LAST CUSTOM_TXT_CDS <Q_REV>
J 0
(-184 103);
DISPLAY 1.212766 (-184 103);
FORCEPROP 1 LAST CUSTOM_TXT_CDS <CON_LAST_MODIFIED>
J 0
(-1885 15);
DISPLAY 0.978723 (-1885 15);
FORCEPROP 1 LAST CUSTOM_TXT_CDS <CON_PAGE_NUM> OF <CON_TOTAL_PAGES>
J 0
(-446 18);
DISPLAY 0.978723 (-446 18);
FORCEPROP 1 LAST Q_TITLE FAN CONTROLLER
J 0
(-9250 75);
DISPLAY 2.446809 (-9250 75);
PAINT GREEN (-9250 75);
FORCEPROP 1 LAST Q_DEPT BU9
J 1
(-3763 49);
DISPLAY 1.957447 (-3763 49);
PAINT GREEN (-3763 49);
FORCEPROP 1 LAST COMMENT_BODY TRUE
J 0
(12 -13);
DISPLAY 0.978723 (12 -13);
PAINT GREEN (12 -13);
DISPLAY INVISIBLE (12 -13);
FORCEPROP 1 LAST CDS_LMAN_SYM_OUTLINE -9475,6775,100,-125
J 0
(0 0);
DISPLAY 0.468085 (0 0);
PAINT GREEN (0 0);
DISPLAY INVISIBLE (0 0);
FORCEPROP 2 LAST CDS_LIB pure_quanta
J 0
(0 0);
DISPLAY INVISIBLE (0 0);
FORCEPROP 2 LAST PAGE_BORDER TRUE
J 0
(-7890 5250);
DISPLAY 0.638298 (-7890 5250);
PAINT PINK (-7890 5250);
DISPLAY INVISIBLE (-7890 5250);
FORCEPROP 2 LAST CDS_XR_PAGE_TITLE CR-152 : @T6G_MB_LIB.T6G(SCH_1):PAGE152
J 0
(-7890 5250);
DISPLAY 0.638298 (-7890 5250);
PAINT PINK (-7890 5250);
DISPLAY INVISIBLE (-7890 5250);
FORCEPROP 2 LAST CUSTOM_TXT_CDS <XR_PAGE_TITLE>
J 0
(-7890 5250);
DISPLAY 0.638298 (-7890 5250);
PAINT PINK (-7890 5250);
DISPLAY INVISIBLE (-7890 5250);
FORCEPROP 0 LAST CDS_CON_LAST_MODIFIED Wed Mar 09 20:27:22 2022
J 0
(-1885 15);
DISPLAY INVISIBLE (-1885 15);
QUIT
